(kicad_pcb
	(version 20241229)
	(generator "pcbnew")
	(generator_version "9.0")
	(general
		(thickness 1.62)
		(legacy_teardrops no)
	)
	(paper "A4")
	(title_block
		(title "OCuLink to 10GbE adapter")
		(date "2026-02-23")
		(rev "1.1.0")
		(company "Antmicro Ltd")
		(comment 1 "www.antmicro.com")
		(comment 9 "footprints 78-83 of 510")
	)
	(layers
		(0 "F.Cu" signal)
		(4 "In1.Cu" signal)
		(6 "In2.Cu" signal)
		(8 "In3.Cu" signal)
		(10 "In4.Cu" signal)
		(12 "In5.Cu" signal)
		(14 "In6.Cu" signal)
		(2 "B.Cu" signal)
		(9 "F.Adhes" user "F.Adhesive")
		(11 "B.Adhes" user "B.Adhesive")
		(13 "F.Paste" user)
		(15 "B.Paste" user)
		(5 "F.SilkS" user "F.Silkscreen")
		(7 "B.SilkS" user "B.Silkscreen")
		(1 "F.Mask" user)
		(3 "B.Mask" user)
		(17 "Dwgs.User" user "User.Drawings")
		(19 "Cmts.User" user "User.Comments")
		(21 "Eco1.User" user "User.Eco1")
		(23 "Eco2.User" user "User.Eco2")
		(25 "Edge.Cuts" user)
		(27 "Margin" user)
		(31 "F.CrtYd" user "F.Courtyard")
		(29 "B.CrtYd" user "B.Courtyard")
		(35 "F.Fab" user)
		(33 "B.Fab" user)
	)
	(footprint "antmicro-footprints:C_0603_1608Metric_EIA"
		(layer "F.Cu")
		(at 66.7 89.1 180)
		(descr "Capacitor SMD 0603, IPC-7351 Density Level A")
		(tags "Capacitor 0603")
		(property "Reference" "C125"
			(at 0.98 0.49 0)
			(layer "F.SilkS")
			(effects
				(font
					(size 0.7 0.7)
					(thickness 0.15)
				)
				(justify right top)
			)
		)
		(property "Value" "C_22u_16V_0603"
			(at -1.42757 1.770288 0)
			(layer "F.Fab")
			(hide yes)
			(effects
				(font
					(size 0.7 0.7)
					(thickness 0.15)
				)
				(justify right top)
			)
		)
		(property "Datasheet" "https://product.samsungsem.com/mlcc/CL10A226MO7JZN.do"
			(at 0 0 0)
			(layer "F.Fab")
			(hide yes)
			(effects
				(font
					(size 1.27 1.27)
					(thickness 0.15)
				)
			)
		)
		(property "Description" "SMD Multilayer Ceramic Capacitor"
			(at 0 0 0)
			(layer "F.Fab")
			(hide yes)
			(effects
				(font
					(size 1.27 1.27)
					(thickness 0.15)
				)
			)
		)
		(property "MPN" "CL10A226MO7JZNC"
			(at 0 0 180)
			(unlocked yes)
			(layer "F.Fab")
			(hide yes)
			(effects
				(font
					(size 1 1)
					(thickness 0.15)
				)
			)
		)
		(property "Manufacturer" "Samsung Electro-Mechanics"
			(at 0 0 180)
			(unlocked yes)
			(layer "F.Fab")
			(hide yes)
			(effects
				(font
					(size 1 1)
					(thickness 0.15)
				)
			)
		)
		(property "License" "Apache-2.0"
			(at 0 0 180)
			(unlocked yes)
			(layer "F.Fab")
			(hide yes)
			(effects
				(font
					(size 1 1)
					(thickness 0.15)
				)
			)
		)
		(property "Author" "Antmicro"
			(at 0 0 180)
			(unlocked yes)
			(layer "F.Fab")
			(hide yes)
			(effects
				(font
					(size 1 1)
					(thickness 0.15)
				)
			)
		)
		(property "Val" "22u"
			(at 0 0 180)
			(unlocked yes)
			(layer "F.Fab")
			(hide yes)
			(effects
				(font
					(size 1 1)
					(thickness 0.15)
				)
			)
		)
		(property "Voltage" "16V"
			(at 0 0 180)
			(unlocked yes)
			(layer "F.Fab")
			(hide yes)
			(effects
				(font
					(size 1 1)
					(thickness 0.15)
				)
			)
		)
		(property "Dielectric" ""
			(at 0 0 180)
			(unlocked yes)
			(layer "F.Fab")
			(hide yes)
			(effects
				(font
					(size 1 1)
					(thickness 0.15)
				)
			)
		)
		(sheetname "/X710-AT2 power/")
		(sheetfile "x710-at2-power.kicad_sch")
		(attr smd)
		(fp_line
			(start -0.15 0.55)
			(end 0.15 0.55)
			(stroke
				(width 0.15)
				(type solid)
			)
			(layer "F.SilkS")
		)
		(fp_line
			(start -0.15 -0.55)
			(end 0.15 -0.55)
			(stroke
				(width 0.15)
				(type solid)
			)
			(layer "F.SilkS")
		)
		(fp_rect
			(start -1.25 -0.65)
			(end 1.25 0.65)
			(stroke
				(width 0.05)
				(type solid)
			)
			(fill no)
			(layer "F.CrtYd")
		)
		(fp_rect
			(start -0.8 -0.45)
			(end 0.8 0.45)
			(stroke
				(width 0.15)
				(type solid)
			)
			(fill no)
			(layer "F.Fab")
		)
		(pad "1" smd roundrect
			(at -0.7 0 180)
			(size 0.8 1.1)
			(layers "F.Cu" "F.Mask" "F.Paste")
			(roundrect_rratio 0.2)
			(net 28 "GND")
			(pintype "passive")
		)
		(pad "2" smd roundrect
			(at 0.7 0 180)
			(size 0.8 1.1)
			(layers "F.Cu" "F.Mask" "F.Paste")
			(roundrect_rratio 0.2)
			(net 9 "VCCD")
			(pintype "passive")
		)
	)
	(footprint "antmicro-footprints:TP_SMD_0.75mm"
		(layer "F.Cu")
		(at 52.05 119.150001 180)
		(property "Reference" "TP17"
			(at 0.41 0.26 0)
			(layer "F.SilkS")
			(hide yes)
			(effects
				(font
					(size 0.7 0.7)
					(thickness 0.15)
				)
				(justify right top)
			)
		)
		(property "Value" "TP_0.75mm_SMD"
			(at 0 1.2 0)
			(layer "F.Fab")
			(hide yes)
			(effects
				(font
					(size 0.7 0.7)
					(thickness 0.15)
				)
				(justify right top)
			)
		)
		(property "Description" "SMT test point"
			(at 0 0 0)
			(layer "F.Fab")
			(hide yes)
			(effects
				(font
					(size 1.27 1.27)
					(thickness 0.15)
				)
			)
		)
		(property "MPN" ""
			(at 0 0 180)
			(unlocked yes)
			(layer "F.Fab")
			(hide yes)
			(effects
				(font
					(size 1 1)
					(thickness 0.15)
				)
			)
		)
		(property "Manufacturer" ""
			(at 0 0 180)
			(unlocked yes)
			(layer "F.Fab")
			(hide yes)
			(effects
				(font
					(size 1 1)
					(thickness 0.15)
				)
			)
		)
		(property "Author" "Antmicro"
			(at 0 0 180)
			(unlocked yes)
			(layer "F.Fab")
			(hide yes)
			(effects
				(font
					(size 1 1)
					(thickness 0.15)
				)
			)
		)
		(property "License" "Apache-2.0"
			(at 0 0 180)
			(unlocked yes)
			(layer "F.Fab")
			(hide yes)
			(effects
				(font
					(size 1 1)
					(thickness 0.15)
				)
			)
		)
		(sheetname "/Power/")
		(sheetfile "power.kicad_sch")
		(attr exclude_from_pos_files exclude_from_bom)
		(fp_circle
			(center 0 0)
			(end 0.475 0)
			(stroke
				(width 0.05)
				(type default)
			)
			(fill no)
			(layer "F.CrtYd")
		)
		(pad "1" smd circle
			(at 0 0 180)
			(size 0.75 0.75)
			(layers "F.Cu" "F.Mask")
			(net 311 "/Power/+DVDD_OUT")
			(pinfunction "1")
			(pintype "passive")
		)
	)
	(footprint "antmicro-footprints:C_0603_1608Metric"
		(layer "F.Cu")
		(at 100.45 99.3)
		(descr "Capacitor SMD 0603")
		(tags "capacitor 0603")
		(property "Reference" "C157"
			(at 4.25 0.45 0)
			(layer "F.SilkS")
			(effects
				(font
					(size 0.7 0.7)
					(thickness 0.15)
				)
				(justify left bottom)
			)
		)
		(property "Value" "C_10u_10V_X7R_0603"
			(at -1.42757 1.770288 0)
			(layer "F.Fab")
			(hide yes)
			(effects
				(font
					(size 0.7 0.7)
					(thickness 0.15)
				)
				(justify left bottom)
			)
		)
		(property "Datasheet" "https://www.murata.com/products/productdetail?partno=GRM188Z71A106KA73%23"
			(at 0 0 0)
			(layer "F.Fab")
			(hide yes)
			(effects
				(font
					(size 1.27 1.27)
					(thickness 0.15)
				)
			)
		)
		(property "Description" "SMD Multilayer Ceramic Capacitor,  10µF, 10V, 0603, ±10%, X7R"
			(at 0 0 0)
			(layer "F.Fab")
			(hide yes)
			(effects
				(font
					(size 1.27 1.27)
					(thickness 0.15)
				)
			)
		)
		(property "MPN" "GRM188Z71A106KA73D"
			(at 0 0 0)
			(unlocked yes)
			(layer "F.Fab")
			(hide yes)
			(effects
				(font
					(size 1 1)
					(thickness 0.15)
				)
			)
		)
		(property "Val" "10u"
			(at 0 0 0)
			(unlocked yes)
			(layer "F.Fab")
			(hide yes)
			(effects
				(font
					(size 1 1)
					(thickness 0.15)
				)
			)
		)
		(property "Voltage" "10V"
			(at 0 0 0)
			(unlocked yes)
			(layer "F.Fab")
			(hide yes)
			(effects
				(font
					(size 1 1)
					(thickness 0.15)
				)
			)
		)
		(property "Dielectric" "X7R"
			(at 0 0 0)
			(unlocked yes)
			(layer "F.Fab")
			(hide yes)
			(effects
				(font
					(size 1 1)
					(thickness 0.15)
				)
			)
		)
		(property "Manufacturer" "Murata"
			(at 0 0 0)
			(unlocked yes)
			(layer "F.Fab")
			(hide yes)
			(effects
				(font
					(size 1 1)
					(thickness 0.15)
				)
			)
		)
		(property "License" "Apache-2.0"
			(at 0 0 0)
			(unlocked yes)
			(layer "F.Fab")
			(hide yes)
			(effects
				(font
					(size 1 1)
					(thickness 0.15)
				)
			)
		)
		(property "Author" "Antmicro"
			(at 0 0 0)
			(unlocked yes)
			(layer "F.Fab")
			(hide yes)
			(effects
				(font
					(size 1 1)
					(thickness 0.15)
				)
			)
		)
		(sheetname "/X710-AT2 power/")
		(sheetfile "x710-at2-power.kicad_sch")
		(attr smd)
		(fp_line
			(start -0.15 -0.4)
			(end 0.15 -0.4)
			(stroke
				(width 0.15)
				(type solid)
			)
			(layer "F.SilkS")
		)
		(fp_line
			(start -0.15 0.4)
			(end 0.15 0.4)
			(stroke
				(width 0.15)
				(type solid)
			)
			(layer "F.SilkS")
		)
		(fp_rect
			(start -1.25 -0.65)
			(end 1.25 0.65)
			(stroke
				(width 0.05)
				(type solid)
			)
			(fill no)
			(layer "F.CrtYd")
		)
		(fp_rect
			(start -0.8 -0.4)
			(end 0.8 0.4)
			(stroke
				(width 0.15)
				(type solid)
			)
			(fill no)
			(layer "F.Fab")
		)
		(pad "1" smd roundrect
			(at -0.7 0)
			(size 0.8 1)
			(layers "F.Cu" "F.Mask" "F.Paste")
			(roundrect_rratio 0.2)
			(net 28 "GND")
			(pintype "passive")
		)
		(pad "2" smd roundrect
			(at 0.7 0)
			(size 0.8 1)
			(layers "F.Cu" "F.Mask" "F.Paste")
			(roundrect_rratio 0.2)
			(net 1 "VCCA")
			(pintype "passive")
		)
	)
	(footprint "antmicro-footprints:C_0603_1608Metric_EIA"
		(layer "F.Cu")
		(at 60.649999 99.500001)
		(descr "Capacitor SMD 0603, IPC-7351 Density Level A")
		(tags "Capacitor 0603")
		(property "Reference" "C25"
			(at -3.459999 -0.660001 0)
			(layer "F.SilkS")
			(effects
				(font
					(size 0.7 0.7)
					(thickness 0.15)
				)
				(justify left bottom)
			)
		)
		(property "Value" "C_22u_16V_0603"
			(at -1.42757 1.770288 0)
			(layer "F.Fab")
			(hide yes)
			(effects
				(font
					(size 0.7 0.7)
					(thickness 0.15)
				)
				(justify left bottom)
			)
		)
		(property "Datasheet" "https://product.samsungsem.com/mlcc/CL10A226MO7JZN.do"
			(at 0 0 0)
			(layer "F.Fab")
			(hide yes)
			(effects
				(font
					(size 1.27 1.27)
					(thickness 0.15)
				)
			)
		)
		(property "Description" "SMD Multilayer Ceramic Capacitor"
			(at 0 0 0)
			(layer "F.Fab")
			(hide yes)
			(effects
				(font
					(size 1.27 1.27)
					(thickness 0.15)
				)
			)
		)
		(property "MPN" "CL10A226MO7JZNC"
			(at 0 0 0)
			(unlocked yes)
			(layer "F.Fab")
			(hide yes)
			(effects
				(font
					(size 1 1)
					(thickness 0.15)
				)
			)
		)
		(property "Manufacturer" "Samsung Electro-Mechanics"
			(at 0 0 0)
			(unlocked yes)
			(layer "F.Fab")
			(hide yes)
			(effects
				(font
					(size 1 1)
					(thickness 0.15)
				)
			)
		)
		(property "License" "Apache-2.0"
			(at 0 0 0)
			(unlocked yes)
			(layer "F.Fab")
			(hide yes)
			(effects
				(font
					(size 1 1)
					(thickness 0.15)
				)
			)
		)
		(property "Author" "Antmicro"
			(at 0 0 0)
			(unlocked yes)
			(layer "F.Fab")
			(hide yes)
			(effects
				(font
					(size 1 1)
					(thickness 0.15)
				)
			)
		)
		(property "Val" "22u"
			(at 0 0 0)
			(unlocked yes)
			(layer "F.Fab")
			(hide yes)
			(effects
				(font
					(size 1 1)
					(thickness 0.15)
				)
			)
		)
		(property "Voltage" "16V"
			(at 0 0 0)
			(unlocked yes)
			(layer "F.Fab")
			(hide yes)
			(effects
				(font
					(size 1 1)
					(thickness 0.15)
				)
			)
		)
		(property "Dielectric" ""
			(at 0 0 0)
			(unlocked yes)
			(layer "F.Fab")
			(hide yes)
			(effects
				(font
					(size 1 1)
					(thickness 0.15)
				)
			)
		)
		(property "Public" "False"
			(at 0 0 0)
			(unlocked yes)
			(layer "F.Fab")
			(hide yes)
			(effects
				(font
					(size 1 1)
					(thickness 0.15)
				)
			)
		)
		(sheetname "/Power/")
		(sheetfile "power.kicad_sch")
		(attr smd)
		(fp_line
			(start -0.15 -0.55)
			(end 0.15 -0.55)
			(stroke
				(width 0.15)
				(type solid)
			)
			(layer "F.SilkS")
		)
		(fp_line
			(start -0.15 0.55)
			(end 0.15 0.55)
			(stroke
				(width 0.15)
				(type solid)
			)
			(layer "F.SilkS")
		)
		(fp_rect
			(start -1.25 -0.65)
			(end 1.25 0.65)
			(stroke
				(width 0.05)
				(type solid)
			)
			(fill no)
			(layer "F.CrtYd")
		)
		(fp_rect
			(start -0.8 -0.45)
			(end 0.8 0.45)
			(stroke
				(width 0.15)
				(type solid)
			)
			(fill no)
			(layer "F.Fab")
		)
		(pad "1" smd roundrect
			(at -0.7 0)
			(size 0.8 1.1)
			(layers "F.Cu" "F.Mask" "F.Paste")
			(roundrect_rratio 0.2)
			(net 28 "GND")
			(pintype "passive")
		)
		(pad "2" smd roundrect
			(at 0.7 0)
			(size 0.8 1.1)
			(layers "F.Cu" "F.Mask" "F.Paste")
			(roundrect_rratio 0.2)
			(net 310 "/Power/+1V88_OUT")
			(pintype "passive")
		)
	)
	(footprint "antmicro-footprints:R_0402_1005Metric"
		(layer "F.Cu")
		(at 99.349999 108.1 180)
		(descr "Resistor SMD 0402")
		(tags "resistor SMD 0402")
		(property "Reference" "R42"
			(at 1.249999 -15.625 0)
			(layer "F.SilkS")
			(effects
				(font
					(size 0.7 0.7)
					(thickness 0.15)
				)
				(justify left bottom)
			)
		)
		(property "Value" "R_22R_0402"
			(at -1.011843 1.772046 0)
			(layer "F.Fab")
			(hide yes)
			(effects
				(font
					(size 0.7 0.7)
					(thickness 0.15)
				)
				(justify right top)
			)
		)
		(property "Datasheet" "https://www.bourns.com/docs/product-datasheets/cr.pdf"
			(at 0 0 0)
			(layer "F.Fab")
			(hide yes)
			(effects
				(font
					(size 1.27 1.27)
					(thickness 0.15)
				)
			)
		)
		(property "Description" "SMD Chip Resistor, 22 ohm, ± 1%, 62.5 mW, 0402 [1005 Metric], Thick Film, General Purpose"
			(at 0 0 0)
			(layer "F.Fab")
			(hide yes)
			(effects
				(font
					(size 1.27 1.27)
					(thickness 0.15)
				)
			)
		)
		(property "MPN" "CR0402-FX-22R0GLF"
			(at 0 0 180)
			(unlocked yes)
			(layer "F.Fab")
			(hide yes)
			(effects
				(font
					(size 1 1)
					(thickness 0.15)
				)
			)
		)
		(property "Manufacturer" "Bourns"
			(at 0 0 180)
			(unlocked yes)
			(layer "F.Fab")
			(hide yes)
			(effects
				(font
					(size 1 1)
					(thickness 0.15)
				)
			)
		)
		(property "License" "Apache-2.0"
			(at 0 0 180)
			(unlocked yes)
			(layer "F.Fab")
			(hide yes)
			(effects
				(font
					(size 1 1)
					(thickness 0.15)
				)
			)
		)
		(property "Author" "Antmicro"
			(at 0 0 180)
			(unlocked yes)
			(layer "F.Fab")
			(hide yes)
			(effects
				(font
					(size 1 1)
					(thickness 0.15)
				)
			)
		)
		(property "Val" "22R"
			(at 0 0 180)
			(unlocked yes)
			(layer "F.Fab")
			(hide yes)
			(effects
				(font
					(size 1 1)
					(thickness 0.15)
				)
			)
		)
		(property "Tolerance" "1%"
			(at 0 0 180)
			(unlocked yes)
			(layer "F.Fab")
			(hide yes)
			(effects
				(font
					(size 1 1)
					(thickness 0.15)
				)
			)
		)
		(sheetname "/X710-AT2 10GbE/")
		(sheetfile "x710-at2-10gbe.kicad_sch")
		(attr smd)
		(fp_rect
			(start -0.925 -0.47)
			(end 0.925 0.47)
			(stroke
				(width 0.05)
				(type default)
			)
			(fill no)
			(layer "F.CrtYd")
		)
		(fp_rect
			(start -0.5 -0.25)
			(end 0.5 0.25)
			(stroke
				(width 0.15)
				(type solid)
			)
			(fill no)
			(layer "F.Fab")
		)
		(pad "1" smd roundrect
			(at -0.48 0 180)
			(size 0.59 0.64)
			(layers "F.Cu" "F.Mask" "F.Paste")
			(roundrect_rratio 0.25)
			(net 143 "/X710-AT2 10GbE/25MHZ_OSC_R.+")
			(pintype "passive")
		)
		(pad "2" smd roundrect
			(at 0.48 0 180)
			(size 0.59 0.64)
			(layers "F.Cu" "F.Mask" "F.Paste")
			(roundrect_rratio 0.25)
			(net 30 "/X710-AT2 10GbE/25MHZ_OSC_AC.+")
			(pintype "passive")
		)
	)
	(footprint "antmicro-footprints:SOD-523"
		(layer "F.Cu")
		(at 79.96 57.771999 180)
		(property "Reference" "D10"
			(at -1.09 -1.678001 0)
			(layer "F.SilkS")
			(effects
				(font
					(size 0.7 0.7)
					(thickness 0.15)
				)
				(justify right top)
			)
		)
		(property "Value" "PESD5Z5_0F"
			(at 0 1.499 0)
			(layer "F.Fab")
			(hide yes)
			(effects
				(font
					(size 0.7 0.7)
					(thickness 0.15)
				)
				(justify right top)
			)
		)
		(property "Datasheet" "https://assets.nexperia.com/documents/data-sheet/PESD5Z5_0.pdf"
			(at 0 0 0)
			(layer "F.Fab")
			(hide yes)
			(effects
				(font
					(size 1.27 1.27)
					(thickness 0.15)
				)
			)
		)
		(property "Description" "Unidirectional TVS, 30 kV,  SOD-523, 5 V, 89 pF"
			(at 0 0 0)
			(layer "F.Fab")
			(hide yes)
			(effects
				(font
					(size 1.27 1.27)
					(thickness 0.15)
				)
			)
		)
		(property "Manufacturer" "Nexperia"
			(at 0 0 180)
			(unlocked yes)
			(layer "F.Fab")
			(hide yes)
			(effects
				(font
					(size 1 1)
					(thickness 0.15)
				)
			)
		)
		(property "MPN" "PESD5Z5.0F"
			(at 0 0 180)
			(unlocked yes)
			(layer "F.Fab")
			(hide yes)
			(effects
				(font
					(size 1 1)
					(thickness 0.15)
				)
			)
		)
		(property "Author" "Antmicro"
			(at 0 0 180)
			(unlocked yes)
			(layer "F.Fab")
			(hide yes)
			(effects
				(font
					(size 1 1)
					(thickness 0.15)
				)
			)
		)
		(property "License" "Apache-2.0"
			(at 0 0 180)
			(unlocked yes)
			(layer "F.Fab")
			(hide yes)
			(effects
				(font
					(size 1 1)
					(thickness 0.15)
				)
			)
		)
		(sheetname "/Power/")
		(sheetfile "power.kicad_sch")
		(attr smd)
		(fp_line
			(start -0.35 -0.5)
			(end -0.35 0.5)
			(stroke
				(width 0.15)
				(type solid)
			)
			(layer "F.SilkS")
		)
		(fp_rect
			(start -1 -0.6)
			(end 1 0.6)
			(stroke
				(width 0.05)
				(type solid)
			)
			(fill no)
			(layer "F.CrtYd")
		)
		(fp_line
			(start 0.65 -0.425)
			(end 0.65 0.423)
			(stroke
				(width 0.15)
				(type solid)
			)
			(layer "F.Fab")
		)
		(fp_line
			(start -0.35 -0.4)
			(end -0.35 0.4)
			(stroke
				(width 0.15)
				(type solid)
			)
			(layer "F.Fab")
		)
		(fp_line
			(start -0.652 0.423)
			(end 0.65 0.423)
			(stroke
				(width 0.15)
				(type solid)
			)
			(layer "F.Fab")
		)
		(fp_line
			(start -0.652 0.423)
			(end -0.652 -0.425)
			(stroke
				(width 0.15)
				(type solid)
			)
			(layer "F.Fab")
		)
		(fp_line
			(start -0.652 -0.425)
			(end 0.65 -0.425)
			(stroke
				(width 0.15)
				(type solid)
			)
			(layer "F.Fab")
		)
		(pad "1" smd roundrect
			(at -0.701 0 180)
			(size 0.5 0.6)
			(layers "F.Cu" "F.Mask" "F.Paste")
			(roundrect_rratio 0.25)
			(net 351 "/Power/+5V_USB")
			(pinfunction "C")
			(pintype "passive")
		)
		(pad "2" smd roundrect
			(at 0.699 0 180)
			(size 0.5 0.6)
			(layers "F.Cu" "F.Mask" "F.Paste")
			(roundrect_rratio 0.25)
			(net 28 "GND")
			(pinfunction "A")
			(pintype "passive")
		)
	)
)
